(kicad_pcb
	(version 20241229)
	(generator "pcbnew")
	(generator_version "9.0")
	(general
		(thickness 1.599998)
		(legacy_teardrops no)
	)
	(paper "A4")
	(title_block
		(title "Artix - Datacenter Secure Control Module (DC-SCM)")
		(date "2024-11-06")
		(rev "1.1.3")
		(comment 9 "footprints 36-41 of 544")
	)
	(layers
		(0 "F.Cu" signal)
		(4 "In1.Cu" signal)
		(6 "In2.Cu" signal)
		(8 "In3.Cu" signal)
		(10 "In4.Cu" signal)
		(12 "In5.Cu" signal)
		(14 "In6.Cu" signal)
		(2 "B.Cu" signal)
		(9 "F.Adhes" user "F.Adhesive")
		(11 "B.Adhes" user "B.Adhesive")
		(13 "F.Paste" user)
		(15 "B.Paste" user)
		(5 "F.SilkS" user "F.Silkscreen")
		(7 "B.SilkS" user "B.Silkscreen")
		(1 "F.Mask" user)
		(3 "B.Mask" user)
		(17 "Dwgs.User" user "User.Drawings")
		(19 "Cmts.User" user "User.Comments")
		(21 "Eco1.User" user "User.Eco1")
		(23 "Eco2.User" user "User.Eco2")
		(25 "Edge.Cuts" user)
		(27 "Margin" user)
		(31 "F.CrtYd" user "F.Courtyard")
		(29 "B.CrtYd" user "B.Courtyard")
		(35 "F.Fab" user)
		(33 "B.Fab" user)
	)
	(footprint "antmicro-footprints:C_0402_1005Metric"
		(layer "F.Cu")
		(at 130.005 168.181 -90)
		(descr "Capacitor SMD 0402")
		(tags "capacitor SMD 0402")
		(property "Reference" "C181"
			(at 0.819 -0.404 90)
			(layer "F.SilkS")
			(effects
				(font
					(size 0.7 0.7)
					(thickness 0.15)
				)
				(justify right bottom)
			)
		)
		(property "Value" "C_100n_6V3_0402"
			(at 0 1.4 90)
			(layer "F.Fab")
			(effects
				(font
					(size 0.7 0.7)
					(thickness 0.15)
				)
				(justify right bottom)
			)
		)
		(property "Datasheet" "https://www.passivecomponent.com/wp-content/uploads/datasheet/WTC_MLCC_General_Purpose.pdf"
			(at 0 0 270)
			(layer "F.Fab")
			(hide yes)
			(effects
				(font
					(size 1.27 1.27)
					(thickness 0.15)
				)
			)
		)
		(property "Description" "SMT Multilayer Ceramic Capacitor, 0.1 µF, 6.3 V, 0402 [1005 Metric], ± 10%, X5R, Walsin MLCC"
			(at 0 0 270)
			(layer "F.Fab")
			(hide yes)
			(effects
				(font
					(size 1.27 1.27)
					(thickness 0.15)
				)
			)
		)
		(property "Author" "Antmicro"
			(at -38.176 298.186 0)
			(layer "F.Fab")
			(hide yes)
			(effects
				(font
					(size 1 1)
					(thickness 0.15)
				)
			)
		)
		(property "Dielectric" ""
			(at -38.176 298.186 0)
			(layer "F.Fab")
			(hide yes)
			(effects
				(font
					(size 1 1)
					(thickness 0.15)
				)
			)
		)
		(property "License" "Apache-2.0"
			(at -38.176 298.186 0)
			(layer "F.Fab")
			(hide yes)
			(effects
				(font
					(size 1 1)
					(thickness 0.15)
				)
			)
		)
		(property "MPN" "0402X104K6R3CT"
			(at -38.176 298.186 0)
			(layer "F.Fab")
			(hide yes)
			(effects
				(font
					(size 1 1)
					(thickness 0.15)
				)
			)
		)
		(property "Manufacturer" "Walsin"
			(at -38.176 298.186 0)
			(layer "F.Fab")
			(hide yes)
			(effects
				(font
					(size 1 1)
					(thickness 0.15)
				)
			)
		)
		(property "Public" "False"
			(at -38.176 298.186 0)
			(layer "F.Fab")
			(hide yes)
			(effects
				(font
					(size 1 1)
					(thickness 0.15)
				)
			)
		)
		(property "Val" "100n"
			(at -38.176 298.186 0)
			(layer "F.Fab")
			(hide yes)
			(effects
				(font
					(size 1 1)
					(thickness 0.15)
				)
			)
		)
		(property "Voltage" ""
			(at -38.176 298.186 0)
			(layer "F.Fab")
			(hide yes)
			(effects
				(font
					(size 1 1)
					(thickness 0.15)
				)
			)
		)
		(sheetname "/PCIe-connector/")
		(sheetfile "pcie-conn.kicad_sch")
		(attr smd)
		(fp_rect
			(start -0.925 -0.47)
			(end 0.925 0.47)
			(stroke
				(width 0.05)
				(type default)
			)
			(fill no)
			(layer "F.CrtYd")
		)
		(fp_line
			(start -0.494 0.248)
			(end -0.494 -0.25)
			(stroke
				(width 0.15)
				(type solid)
			)
			(layer "F.Fab")
		)
		(fp_line
			(start 0.504 0.248)
			(end -0.494 0.248)
			(stroke
				(width 0.15)
				(type solid)
			)
			(layer "F.Fab")
		)
		(fp_line
			(start -0.494 -0.25)
			(end 0.504 -0.25)
			(stroke
				(width 0.15)
				(type solid)
			)
			(layer "F.Fab")
		)
		(fp_line
			(start 0.504 -0.25)
			(end 0.504 0.248)
			(stroke
				(width 0.15)
				(type solid)
			)
			(layer "F.Fab")
		)
		(pad "1" smd roundrect
			(at -0.48 0 270)
			(size 0.59 0.64)
			(layers "F.Cu" "F.Mask" "F.Paste")
			(roundrect_rratio 0.25)
			(net 375 "/PCIe-connector/PCIE_HPM_TX2_C_N")
			(pintype "passive")
		)
		(pad "2" smd roundrect
			(at 0.48 0 270)
			(size 0.59 0.64)
			(layers "F.Cu" "F.Mask" "F.Paste")
			(roundrect_rratio 0.25)
			(net 357 "PCIE_HPM_TX[2]_N")
			(pintype "passive")
		)
	)
	(footprint "antmicro-footprints:R_0402_1005Metric"
		(layer "F.Cu")
		(at 73.15 97.995 180)
		(descr "Resistor SMD 0402")
		(tags "resistor SMD 0402")
		(property "Reference" "R98"
			(at -1.05 0.495 0)
			(layer "F.SilkS")
			(effects
				(font
					(size 0.7 0.7)
					(thickness 0.15)
				)
				(justify right bottom)
			)
		)
		(property "Value" "R_1k_0402"
			(at 0 1.4 0)
			(layer "F.Fab")
			(effects
				(font
					(size 0.7 0.7)
					(thickness 0.15)
				)
				(justify right bottom)
			)
		)
		(property "Datasheet" "https://www.bourns.com/docs/product-datasheets/cr.pdf"
			(at 0 0 180)
			(layer "F.Fab")
			(hide yes)
			(effects
				(font
					(size 1.27 1.27)
					(thickness 0.15)
				)
			)
		)
		(property "Description" "SMD Chip Resistor, 1 kohm, ± 1%, 63 mW, 0402 [1005 Metric], Thick Film, General Purpose"
			(at 0 0 180)
			(layer "F.Fab")
			(hide yes)
			(effects
				(font
					(size 1.27 1.27)
					(thickness 0.15)
				)
			)
		)
		(property "Author" "Antmicro"
			(at 146.3 195.99 0)
			(layer "F.Fab")
			(hide yes)
			(effects
				(font
					(size 1 1)
					(thickness 0.15)
				)
			)
		)
		(property "License" "Apache-2.0"
			(at 146.3 195.99 0)
			(layer "F.Fab")
			(hide yes)
			(effects
				(font
					(size 1 1)
					(thickness 0.15)
				)
			)
		)
		(property "MPN" "CR0402-FX-1001GLF"
			(at 146.3 195.99 0)
			(layer "F.Fab")
			(hide yes)
			(effects
				(font
					(size 1 1)
					(thickness 0.15)
				)
			)
		)
		(property "Manufacturer" "Bourns"
			(at 146.3 195.99 0)
			(layer "F.Fab")
			(hide yes)
			(effects
				(font
					(size 1 1)
					(thickness 0.15)
				)
			)
		)
		(property "Tolerance" "1%"
			(at 146.3 195.99 0)
			(layer "F.Fab")
			(hide yes)
			(effects
				(font
					(size 1 1)
					(thickness 0.15)
				)
			)
		)
		(property "Val" "1k"
			(at 146.3 195.99 0)
			(layer "F.Fab")
			(hide yes)
			(effects
				(font
					(size 1 1)
					(thickness 0.15)
				)
			)
		)
		(sheetname "/Power supply/")
		(sheetfile "power-supply.kicad_sch")
		(attr smd)
		(fp_rect
			(start -0.925 -0.47)
			(end 0.925 0.47)
			(stroke
				(width 0.05)
				(type default)
			)
			(fill no)
			(layer "F.CrtYd")
		)
		(fp_rect
			(start -0.5 -0.25)
			(end 0.5 0.25)
			(stroke
				(width 0.15)
				(type solid)
			)
			(fill no)
			(layer "F.Fab")
		)
		(pad "1" smd roundrect
			(at -0.48 0 180)
			(size 0.59 0.64)
			(layers "F.Cu" "F.Mask" "F.Paste")
			(roundrect_rratio 0.25)
			(net 224 "Net-(D8-A)")
			(pintype "passive")
		)
		(pad "2" smd roundrect
			(at 0.48 0 180)
			(size 0.59 0.64)
			(layers "F.Cu" "F.Mask" "F.Paste")
			(roundrect_rratio 0.25)
			(net 2 "VCC3V3")
			(pintype "passive")
		)
	)
	(footprint "antmicro-footprints:R_0402_1005Metric"
		(layer "F.Cu")
		(at 73.15 93.931 180)
		(descr "Resistor SMD 0402")
		(tags "resistor SMD 0402")
		(property "Reference" "R97"
			(at -1.05 0.531 0)
			(layer "F.SilkS")
			(effects
				(font
					(size 0.7 0.7)
					(thickness 0.15)
				)
				(justify right bottom)
			)
		)
		(property "Value" "R_1k_0402"
			(at 0 1.4 0)
			(layer "F.Fab")
			(effects
				(font
					(size 0.7 0.7)
					(thickness 0.15)
				)
				(justify right bottom)
			)
		)
		(property "Datasheet" "https://www.bourns.com/docs/product-datasheets/cr.pdf"
			(at 0 0 180)
			(layer "F.Fab")
			(hide yes)
			(effects
				(font
					(size 1.27 1.27)
					(thickness 0.15)
				)
			)
		)
		(property "Description" "SMD Chip Resistor, 1 kohm, ± 1%, 63 mW, 0402 [1005 Metric], Thick Film, General Purpose"
			(at 0 0 180)
			(layer "F.Fab")
			(hide yes)
			(effects
				(font
					(size 1.27 1.27)
					(thickness 0.15)
				)
			)
		)
		(property "Author" "Antmicro"
			(at 146.3 187.862 0)
			(layer "F.Fab")
			(hide yes)
			(effects
				(font
					(size 1 1)
					(thickness 0.15)
				)
			)
		)
		(property "License" "Apache-2.0"
			(at 146.3 187.862 0)
			(layer "F.Fab")
			(hide yes)
			(effects
				(font
					(size 1 1)
					(thickness 0.15)
				)
			)
		)
		(property "MPN" "CR0402-FX-1001GLF"
			(at 146.3 187.862 0)
			(layer "F.Fab")
			(hide yes)
			(effects
				(font
					(size 1 1)
					(thickness 0.15)
				)
			)
		)
		(property "Manufacturer" "Bourns"
			(at 146.3 187.862 0)
			(layer "F.Fab")
			(hide yes)
			(effects
				(font
					(size 1 1)
					(thickness 0.15)
				)
			)
		)
		(property "Tolerance" "1%"
			(at 146.3 187.862 0)
			(layer "F.Fab")
			(hide yes)
			(effects
				(font
					(size 1 1)
					(thickness 0.15)
				)
			)
		)
		(property "Val" "1k"
			(at 146.3 187.862 0)
			(layer "F.Fab")
			(hide yes)
			(effects
				(font
					(size 1 1)
					(thickness 0.15)
				)
			)
		)
		(sheetname "/Power supply/")
		(sheetfile "power-supply.kicad_sch")
		(attr smd)
		(fp_rect
			(start -0.925 -0.47)
			(end 0.925 0.47)
			(stroke
				(width 0.05)
				(type default)
			)
			(fill no)
			(layer "F.CrtYd")
		)
		(fp_rect
			(start -0.5 -0.25)
			(end 0.5 0.25)
			(stroke
				(width 0.15)
				(type solid)
			)
			(fill no)
			(layer "F.Fab")
		)
		(pad "1" smd roundrect
			(at -0.48 0 180)
			(size 0.59 0.64)
			(layers "F.Cu" "F.Mask" "F.Paste")
			(roundrect_rratio 0.25)
			(net 219 "Net-(D7-A)")
			(pintype "passive")
		)
		(pad "2" smd roundrect
			(at 0.48 0 180)
			(size 0.59 0.64)
			(layers "F.Cu" "F.Mask" "F.Paste")
			(roundrect_rratio 0.25)
			(net 2 "VCC3V3")
			(pintype "passive")
		)
	)
	(footprint "antmicro-footprints:R_0402_1005Metric"
		(layer "F.Cu")
		(at 73.15 95.963 180)
		(descr "Resistor SMD 0402")
		(tags "resistor SMD 0402")
		(property "Reference" "R96"
			(at -1.05 0.495 0)
			(layer "F.SilkS")
			(effects
				(font
					(size 0.7 0.7)
					(thickness 0.15)
				)
				(justify right bottom)
			)
		)
		(property "Value" "R_1k_0402"
			(at 0 1.4 0)
			(layer "F.Fab")
			(effects
				(font
					(size 0.7 0.7)
					(thickness 0.15)
				)
				(justify right bottom)
			)
		)
		(property "Datasheet" "https://www.bourns.com/docs/product-datasheets/cr.pdf"
			(at 0 0 180)
			(layer "F.Fab")
			(hide yes)
			(effects
				(font
					(size 1.27 1.27)
					(thickness 0.15)
				)
			)
		)
		(property "Description" "SMD Chip Resistor, 1 kohm, ± 1%, 63 mW, 0402 [1005 Metric], Thick Film, General Purpose"
			(at 0 0 180)
			(layer "F.Fab")
			(hide yes)
			(effects
				(font
					(size 1.27 1.27)
					(thickness 0.15)
				)
			)
		)
		(property "Author" "Antmicro"
			(at 146.3 191.926 0)
			(layer "F.Fab")
			(hide yes)
			(effects
				(font
					(size 1 1)
					(thickness 0.15)
				)
			)
		)
		(property "License" "Apache-2.0"
			(at 146.3 191.926 0)
			(layer "F.Fab")
			(hide yes)
			(effects
				(font
					(size 1 1)
					(thickness 0.15)
				)
			)
		)
		(property "MPN" "CR0402-FX-1001GLF"
			(at 146.3 191.926 0)
			(layer "F.Fab")
			(hide yes)
			(effects
				(font
					(size 1 1)
					(thickness 0.15)
				)
			)
		)
		(property "Manufacturer" "Bourns"
			(at 146.3 191.926 0)
			(layer "F.Fab")
			(hide yes)
			(effects
				(font
					(size 1 1)
					(thickness 0.15)
				)
			)
		)
		(property "Tolerance" "1%"
			(at 146.3 191.926 0)
			(layer "F.Fab")
			(hide yes)
			(effects
				(font
					(size 1 1)
					(thickness 0.15)
				)
			)
		)
		(property "Val" "1k"
			(at 146.3 191.926 0)
			(layer "F.Fab")
			(hide yes)
			(effects
				(font
					(size 1 1)
					(thickness 0.15)
				)
			)
		)
		(sheetname "/Power supply/")
		(sheetfile "power-supply.kicad_sch")
		(attr smd)
		(fp_rect
			(start -0.925 -0.47)
			(end 0.925 0.47)
			(stroke
				(width 0.05)
				(type default)
			)
			(fill no)
			(layer "F.CrtYd")
		)
		(fp_rect
			(start -0.5 -0.25)
			(end 0.5 0.25)
			(stroke
				(width 0.15)
				(type solid)
			)
			(fill no)
			(layer "F.Fab")
		)
		(pad "1" smd roundrect
			(at -0.48 0 180)
			(size 0.59 0.64)
			(layers "F.Cu" "F.Mask" "F.Paste")
			(roundrect_rratio 0.25)
			(net 217 "Net-(D6-A)")
			(pintype "passive")
		)
		(pad "2" smd roundrect
			(at 0.48 0 180)
			(size 0.59 0.64)
			(layers "F.Cu" "F.Mask" "F.Paste")
			(roundrect_rratio 0.25)
			(net 2 "VCC3V3")
			(pintype "passive")
		)
	)
	(footprint "antmicro-footprints:R_0402_1005Metric"
		(layer "F.Cu")
		(at 73.15 91.9 180)
		(descr "Resistor SMD 0402")
		(tags "resistor SMD 0402")
		(property "Reference" "R94"
			(at -1.05 0.495 0)
			(layer "F.SilkS")
			(effects
				(font
					(size 0.7 0.7)
					(thickness 0.15)
				)
				(justify right bottom)
			)
		)
		(property "Value" "R_1k_0402"
			(at 0 1.4 0)
			(layer "F.Fab")
			(effects
				(font
					(size 0.7 0.7)
					(thickness 0.15)
				)
				(justify right bottom)
			)
		)
		(property "Datasheet" "https://www.bourns.com/docs/product-datasheets/cr.pdf"
			(at 0 0 180)
			(layer "F.Fab")
			(hide yes)
			(effects
				(font
					(size 1.27 1.27)
					(thickness 0.15)
				)
			)
		)
		(property "Description" "SMD Chip Resistor, 1 kohm, ± 1%, 63 mW, 0402 [1005 Metric], Thick Film, General Purpose"
			(at 0 0 180)
			(layer "F.Fab")
			(hide yes)
			(effects
				(font
					(size 1.27 1.27)
					(thickness 0.15)
				)
			)
		)
		(property "Author" "Antmicro"
			(at 146.3 183.8 0)
			(layer "F.Fab")
			(hide yes)
			(effects
				(font
					(size 1 1)
					(thickness 0.15)
				)
			)
		)
		(property "License" "Apache-2.0"
			(at 146.3 183.8 0)
			(layer "F.Fab")
			(hide yes)
			(effects
				(font
					(size 1 1)
					(thickness 0.15)
				)
			)
		)
		(property "MPN" "CR0402-FX-1001GLF"
			(at 146.3 183.8 0)
			(layer "F.Fab")
			(hide yes)
			(effects
				(font
					(size 1 1)
					(thickness 0.15)
				)
			)
		)
		(property "Manufacturer" "Bourns"
			(at 146.3 183.8 0)
			(layer "F.Fab")
			(hide yes)
			(effects
				(font
					(size 1 1)
					(thickness 0.15)
				)
			)
		)
		(property "Tolerance" "1%"
			(at 146.3 183.8 0)
			(layer "F.Fab")
			(hide yes)
			(effects
				(font
					(size 1 1)
					(thickness 0.15)
				)
			)
		)
		(property "Val" "1k"
			(at 146.3 183.8 0)
			(layer "F.Fab")
			(hide yes)
			(effects
				(font
					(size 1 1)
					(thickness 0.15)
				)
			)
		)
		(sheetname "/Power supply/")
		(sheetfile "power-supply.kicad_sch")
		(attr smd)
		(fp_rect
			(start -0.925 -0.47)
			(end 0.925 0.47)
			(stroke
				(width 0.05)
				(type default)
			)
			(fill no)
			(layer "F.CrtYd")
		)
		(fp_rect
			(start -0.5 -0.25)
			(end 0.5 0.25)
			(stroke
				(width 0.15)
				(type solid)
			)
			(fill no)
			(layer "F.Fab")
		)
		(pad "1" smd roundrect
			(at -0.48 0 180)
			(size 0.59 0.64)
			(layers "F.Cu" "F.Mask" "F.Paste")
			(roundrect_rratio 0.25)
			(net 208 "Net-(D4-A)")
			(pintype "passive")
		)
		(pad "2" smd roundrect
			(at 0.48 0 180)
			(size 0.59 0.64)
			(layers "F.Cu" "F.Mask" "F.Paste")
			(roundrect_rratio 0.25)
			(net 2 "VCC3V3")
			(pintype "passive")
		)
	)
	(footprint "antmicro-footprints:PinHeader_1x3_P2.54mm_Drill1.1mm"
		(layer "F.Cu")
		(at 144.565 107.186 -90)
		(property "Reference" "J13"
			(at -1.6 -1.8 270)
			(layer "F.SilkS")
			(effects
				(font
					(size 0.7 0.7)
					(thickness 0.15)
				)
				(justify left bottom)
			)
		)
		(property "Value" "PinHeader_1x3_P2.54mm_Drill1.1mm"
			(at -1.6 2.7 270)
			(layer "F.Fab")
			(effects
				(font
					(size 0.7 0.7)
					(thickness 0.15)
				)
				(justify left bottom)
			)
		)
		(property "Datasheet" "https://katalog.we-online.de/em/datasheet/6130xx11121.pdf"
			(at 0 0 270)
			(layer "F.Fab")
			(hide yes)
			(effects
				(font
					(size 1.27 1.27)
					(thickness 0.15)
				)
			)
		)
		(property "Description" "Pin Header, Vertical, Board-to-Board, 2.54 mm, 1 Rows, 3 Contacts, Through Hole Straight, WR-PHD"
			(at 0 0 270)
			(layer "F.Fab")
			(hide yes)
			(effects
				(font
					(size 1.27 1.27)
					(thickness 0.15)
				)
			)
		)
		(property "Author" "Antmicro"
			(at 37.379 251.751 0)
			(layer "F.Fab")
			(hide yes)
			(effects
				(font
					(size 1 1)
					(thickness 0.15)
				)
			)
		)
		(property "License" "Apache-2.0"
			(at 37.379 251.751 0)
			(layer "F.Fab")
			(hide yes)
			(effects
				(font
					(size 1 1)
					(thickness 0.15)
				)
			)
		)
		(property "MPN" "61300311121"
			(at 37.379 251.751 0)
			(layer "F.Fab")
			(hide yes)
			(effects
				(font
					(size 1 1)
					(thickness 0.15)
				)
			)
		)
		(property "Manufacturer" "Würth Elektronik"
			(at 37.379 251.751 0)
			(layer "F.Fab")
			(hide yes)
			(effects
				(font
					(size 1 1)
					(thickness 0.15)
				)
			)
		)
		(property "VSD_class" "IO Header"
			(at 37.379 251.751 0)
			(layer "F.Fab")
			(hide yes)
			(effects
				(font
					(size 1 1)
					(thickness 0.15)
				)
			)
		)
		(sheetname "/FPGA banks 34-35 & CFG/")
		(sheetfile "fpga-banks-34-25-cfg.kicad_sch")
		(attr through_hole)
		(fp_line
			(start -1.401 1.398)
			(end -0.902 1.398)
			(stroke
				(width 0.15)
				(type solid)
			)
			(layer "F.SilkS")
		)
		(fp_line
			(start -1.401 1.398)
			(end -1.401 0.9)
			(stroke
				(width 0.15)
				(type solid)
			)
			(layer "F.SilkS")
		)
		(fp_line
			(start 6.499 1.398)
			(end 5.999 1.398)
			(stroke
				(width 0.15)
				(type solid)
			)
			(layer "F.SilkS")
		)
		(fp_line
			(start 6.499 1.398)
			(end 6.499 0.9)
			(stroke
				(width 0.15)
				(type solid)
			)
			(layer "F.SilkS")
		)
		(fp_line
			(start -1.401 -1.401)
			(end -1.401 -0.902)
			(stroke
				(width 0.15)
				(type solid)
			)
			(layer "F.SilkS")
		)
		(fp_line
			(start -1.401 -1.401)
			(end -0.902 -1.401)
			(stroke
				(width 0.15)
				(type solid)
			)
			(layer "F.SilkS")
		)
		(fp_line
			(start 6.499 -1.401)
			(end 6.499 -0.902)
			(stroke
				(width 0.15)
				(type solid)
			)
			(layer "F.SilkS")
		)
		(fp_line
			(start 6.499 -1.401)
			(end 5.999 -1.401)
			(stroke
				(width 0.15)
				(type solid)
			)
			(layer "F.SilkS")
		)
		(fp_line
			(start -1.52 1.5)
			(end 6.58 1.5)
			(stroke
				(width 0.05)
				(type solid)
			)
			(layer "F.CrtYd")
		)
		(fp_line
			(start -1.52 -1.52)
			(end -1.52 1.5)
			(stroke
				(width 0.05)
				(type solid)
			)
			(layer "F.CrtYd")
		)
		(fp_line
			(start -1.52 -1.52)
			(end 6.58 -1.52)
			(stroke
				(width 0.05)
				(type solid)
			)
			(layer "F.CrtYd")
		)
		(fp_line
			(start 6.58 -1.52)
			(end 6.58 1.5)
			(stroke
				(width 0.05)
				(type solid)
			)
			(layer "F.CrtYd")
		)
		(fp_line
			(start -1.27 1.269)
			(end 6.349 1.269)
			(stroke
				(width 0.15)
				(type solid)
			)
			(layer "F.Fab")
		)
		(fp_line
			(start -1.27 -1.27)
			(end -1.27 1.269)
			(stroke
				(width 0.15)
				(type solid)
			)
			(layer "F.Fab")
		)
		(fp_line
			(start -1.27 -1.27)
			(end 6.349 -1.27)
			(stroke
				(width 0.15)
				(type solid)
			)
			(layer "F.Fab")
		)
		(fp_line
			(start 6.349 -1.27)
			(end 6.349 1.269)
			(stroke
				(width 0.15)
				(type solid)
			)
			(layer "F.Fab")
		)
		(pad "1" thru_hole rect
			(at 0 0 270)
			(size 1.7 1.7)
			(drill 1.1)
			(layers "*.Cu" "*.Mask")
			(remove_unused_layers no)
			(net 2 "VCC3V3")
			(pintype "passive")
		)
		(pad "2" thru_hole circle
			(at 2.539 0 270)
			(size 1.7 1.7)
			(drill 1.1)
			(layers "*.Cu" "*.Mask")
			(remove_unused_layers no)
			(net 259 "/FPGA banks 34-35 & CFG/MODE2")
			(pintype "passive")
		)
		(pad "3" thru_hole circle
			(at 5.078 0 270)
			(size 1.7 1.7)
			(drill 1.1)
			(layers "*.Cu" "*.Mask")
			(remove_unused_layers no)
			(net 1 "GND")
			(pintype "passive")
		)
	)
)
